(kicad_pcb
	(version 20260206)
	(generator "pcbnew")
	(generator_version "10.0")
	(general
		(thickness 1.6)
		(legacy_teardrops no)
	)
	(paper "A4")
	(title_block
		(title "panther-plus-userver — 13130-1b_20150205.brd")
		(comment 1 "Honey Badger (Wiwynn) / footprint 1214 of 1509 (DIMM3), pads 86-92 of 210")
	)
	(layers
		(0 "F.Cu" signal "TOP")
		(4 "In1.Cu" signal "L2")
		(6 "In2.Cu" signal "L3")
		(8 "In3.Cu" signal "L4")
		(10 "In4.Cu" signal "L5")
		(12 "In5.Cu" signal "L6")
		(14 "In6.Cu" signal "L7")
		(16 "In7.Cu" signal "L8")
		(18 "In8.Cu" signal "L9")
		(20 "In9.Cu" signal "L10")
		(22 "In10.Cu" signal "L11")
		(2 "B.Cu" signal "BOTTOM")
		(9 "F.Adhes" user "F.Adhesive")
		(11 "B.Adhes" user "B.Adhesive")
		(13 "F.Paste" user "Package Geometry/Pastemask Top")
		(15 "B.Paste" user "Package Geometry/Pastemask Bottom")
		(5 "F.SilkS" user "Ref Des/Silkscreen Top")
		(7 "B.SilkS" user "Ref Des/Silkscreen Bottom")
		(1 "F.Mask" user "Board Geometry/Soldermask Top")
		(3 "B.Mask" user "Board Geometry/Soldermask Bottom")
		(17 "Dwgs.User" user "User.Drawings")
		(19 "Cmts.User" user "User.Comments")
		(21 "Eco1.User" user "User.Eco1")
		(23 "Eco2.User" user "User.Eco2")
		(25 "Edge.Cuts" user "Board Geometry/Outline")
		(27 "Margin" user)
		(31 "F.CrtYd" user "Package Geometry/Place Bound Top")
		(29 "B.CrtYd" user "Package Geometry/Place Bound Bottom")
		(35 "F.Fab" user "Ref Des/Assembly Top")
		(33 "B.Fab" user "Ref Des/Assembly Bottom")
	)
	(footprint ""
		(layer "B.Cu")
		(at 159.999934 -5.790692)
		(property "Reference" "DIMM3"
			(at 0 0 0)
			(layer "B.SilkS")
			(hide yes)
			(effects
				(font
					(size 1.27 1.27)
				)
				(justify mirror)
			)
		)
		(property "Value" "DDR3-204P-142-COLAY-1-GP-U"
			(at 41.312338 -16.676878 0)
			(unlocked yes)
			(layer "B.Fab")
			(hide yes)
			(effects
				(font
					(size 1.016 1.016)
					(thickness 0.1524)
				)
				(justify mirror)
			)
		)
		(property "Device Type" "AS0A626-J8R6-7H-COLAY-1"
			(at 41.312338 -18.200878 0)
			(unlocked yes)
			(layer "B.Fab")
			(hide yes)
			(effects
				(font
					(size 1.016 1.016)
					(thickness 0.1524)
				)
				(justify mirror)
			)
		)
		(duplicate_pad_numbers_are_jumpers no)
		(pad "84" smd custom
			(at -4.350004 4.100068 180)
			(size 0.1143 0.1143)
			(layers "B.Cu" "B.Mask" "B.Paste")
			(net "DDR3_M_B_VREF_CA")
			(options
				(clearance outline)
				(anchor circle)
			)
			(primitives
				(gr_poly
					(pts
						(xy 0 -0.9017) (xy -0.03175 -0.89916) (xy -0.0635 -0.889) (xy -0.09144 -0.87376) (xy -0.11684 -0.85344)
						(xy -0.13716 -0.82804) (xy -0.1524 -0.8001) (xy -0.16256 -0.76835) (xy -0.1651 -0.7366) (xy -0.1651 -0.11938)
						(xy -0.17272 -0.11176) (xy -0.19812 -0.0762) (xy -0.2032 -0.06604) (xy -0.20701 -0.05715) (xy -0.21209 -0.04699)
						(xy -0.2159 -0.03683) (xy -0.21844 -0.02667) (xy -0.22225 -0.01524) (xy -0.22352 -0.00508) (xy -0.22606 0.00508)
						(xy -0.22733 0.01651) (xy -0.22733 0.02667) (xy -0.2286 0.0381) (xy -0.22733 0.04953) (xy -0.22733 0.05969)
						(xy -0.22606 0.07112) (xy -0.22352 0.08128) (xy -0.22225 0.09144) (xy -0.21844 0.10287) (xy -0.2159 0.11303)
						(xy -0.21209 0.12319) (xy -0.20701 0.13335) (xy -0.2032 0.14224) (xy -0.19812 0.1524) (xy -0.17272 0.18796)
						(xy -0.1651 0.19558) (xy -0.1651 0.7366) (xy -0.16256 0.76835) (xy -0.1524 0.8001) (xy -0.13716 0.82804)
						(xy -0.11684 0.85344) (xy -0.09144 0.87376) (xy -0.0635 0.889) (xy -0.03175 0.89916) (xy 0 0.9017)
						(xy 0.03175 0.89916) (xy 0.0635 0.889) (xy 0.09144 0.87376) (xy 0.11684 0.85344) (xy 0.13716 0.82804)
						(xy 0.1524 0.8001) (xy 0.16256 0.76835) (xy 0.1651 0.7366) (xy 0.1651 0.19685) (xy 0.17272 0.18923)
						(xy 0.17907 0.18034) (xy 0.18669 0.17145) (xy 0.19177 0.16256) (xy 0.19812 0.15367) (xy 0.20828 0.13335)
						(xy 0.21971 0.10287) (xy 0.22225 0.09271) (xy 0.22479 0.08128) (xy 0.22606 0.07112) (xy 0.2286 0.05969)
						(xy 0.2286 0.01651) (xy 0.22606 0.00508) (xy 0.22479 -0.00508) (xy 0.22225 -0.01651) (xy 0.21971 -0.02667)
						(xy 0.20828 -0.05715) (xy 0.19812 -0.07747) (xy 0.19177 -0.08636) (xy 0.18669 -0.09525) (xy 0.17907 -0.10414)
						(xy 0.17272 -0.11303) (xy 0.1651 -0.12065) (xy 0.1651 -0.7366) (xy 0.16256 -0.76835) (xy 0.1524 -0.8001)
						(xy 0.13716 -0.82804) (xy 0.11684 -0.85344) (xy 0.09144 -0.87376) (xy 0.0635 -0.889) (xy 0.03175 -0.89916)
					)
					(width 0)
					(fill yes)
				)
			)
		)
		(pad "85" smd custom
			(at -4.05003 -4.100068 180)
			(size 0.1143 0.1143)
			(layers "B.Cu" "B.Mask" "B.Paste")
			(net "PV_VDDR")
			(options
				(clearance outline)
				(anchor circle)
			)
			(primitives
				(gr_poly
					(pts
						(xy 0 -0.9017) (xy -0.03175 -0.89916) (xy -0.0635 -0.889) (xy -0.09144 -0.87376) (xy -0.11684 -0.85344)
						(xy -0.13716 -0.82804) (xy -0.1524 -0.8001) (xy -0.16256 -0.76835) (xy -0.1651 -0.7366) (xy -0.1651 -0.44958)
						(xy -0.17272 -0.44196) (xy -0.19812 -0.4064) (xy -0.2032 -0.39624) (xy -0.20701 -0.38735) (xy -0.21209 -0.37719)
						(xy -0.2159 -0.36703) (xy -0.21844 -0.35687) (xy -0.22225 -0.34544) (xy -0.22352 -0.33528) (xy -0.22606 -0.32512)
						(xy -0.22733 -0.31369) (xy -0.22733 -0.30353) (xy -0.2286 -0.2921) (xy -0.22733 -0.28067) (xy -0.22733 -0.27051)
						(xy -0.22606 -0.25908) (xy -0.22352 -0.24892) (xy -0.22225 -0.23876) (xy -0.21844 -0.22733) (xy -0.2159 -0.21717)
						(xy -0.21209 -0.20701) (xy -0.20701 -0.19685) (xy -0.2032 -0.18796) (xy -0.19812 -0.1778) (xy -0.17272 -0.14224)
						(xy -0.1651 -0.13462) (xy -0.1651 0.7366) (xy -0.16256 0.76835) (xy -0.1524 0.8001) (xy -0.13716 0.82804)
						(xy -0.11684 0.85344) (xy -0.09144 0.87376) (xy -0.0635 0.889) (xy -0.03175 0.89916) (xy 0 0.9017)
						(xy 0.03175 0.89916) (xy 0.0635 0.889) (xy 0.09144 0.87376) (xy 0.11684 0.85344) (xy 0.13716 0.82804)
						(xy 0.1524 0.8001) (xy 0.16256 0.76835) (xy 0.1651 0.7366) (xy 0.1651 -0.13462) (xy 0.17272 -0.14224)
						(xy 0.19812 -0.1778) (xy 0.2032 -0.18796) (xy 0.20701 -0.19685) (xy 0.21209 -0.20701) (xy 0.2159 -0.21717)
						(xy 0.21844 -0.22733) (xy 0.22225 -0.23876) (xy 0.22352 -0.24892) (xy 0.22606 -0.25908) (xy 0.22733 -0.27051)
						(xy 0.22733 -0.28067) (xy 0.2286 -0.2921) (xy 0.22733 -0.30353) (xy 0.22733 -0.31369) (xy 0.22606 -0.32512)
						(xy 0.22352 -0.33528) (xy 0.22225 -0.34544) (xy 0.21844 -0.35687) (xy 0.2159 -0.36703) (xy 0.21209 -0.37719)
						(xy 0.20701 -0.38735) (xy 0.2032 -0.39624) (xy 0.19812 -0.4064) (xy 0.17272 -0.44196) (xy 0.1651 -0.44958)
						(xy 0.1651 -0.7366) (xy 0.16256 -0.76835) (xy 0.1524 -0.8001) (xy 0.13716 -0.82804) (xy 0.11684 -0.85344)
						(xy 0.09144 -0.87376) (xy 0.0635 -0.889) (xy 0.03175 -0.89916)
					)
					(width 0)
					(fill yes)
				)
			)
		)
		(pad "86" smd custom
			(at -3.750056 4.100068 180)
			(size 0.1143 0.1143)
			(layers "B.Cu" "B.Mask" "B.Paste")
			(net "PV_VDDR")
			(options
				(clearance outline)
				(anchor circle)
			)
			(primitives
				(gr_poly
					(pts
						(xy 0 -0.9017) (xy -0.03175 -0.89916) (xy -0.0635 -0.889) (xy -0.09144 -0.87376) (xy -0.11684 -0.85344)
						(xy -0.13716 -0.82804) (xy -0.1524 -0.8001) (xy -0.16256 -0.76835) (xy -0.1651 -0.7366) (xy -0.1651 0.13462)
						(xy -0.17272 0.14224) (xy -0.19812 0.1778) (xy -0.2032 0.18796) (xy -0.20701 0.19685) (xy -0.21209 0.20701)
						(xy -0.2159 0.21717) (xy -0.21844 0.22733) (xy -0.22225 0.23876) (xy -0.22352 0.24892) (xy -0.22606 0.25908)
						(xy -0.22733 0.27051) (xy -0.22733 0.28067) (xy -0.2286 0.2921) (xy -0.22733 0.30353) (xy -0.22733 0.31369)
						(xy -0.22606 0.32512) (xy -0.22352 0.33528) (xy -0.22225 0.34544) (xy -0.21844 0.35687) (xy -0.2159 0.36703)
						(xy -0.21209 0.37719) (xy -0.20701 0.38735) (xy -0.2032 0.39624) (xy -0.19812 0.4064) (xy -0.17272 0.44196)
						(xy -0.1651 0.44958) (xy -0.1651 0.7366) (xy -0.16256 0.76835) (xy -0.1524 0.8001) (xy -0.13716 0.82804)
						(xy -0.11684 0.85344) (xy -0.09144 0.87376) (xy -0.0635 0.889) (xy -0.03175 0.89916) (xy 0 0.9017)
						(xy 0.03175 0.89916) (xy 0.0635 0.889) (xy 0.09144 0.87376) (xy 0.11684 0.85344) (xy 0.13716 0.82804)
						(xy 0.1524 0.8001) (xy 0.16256 0.76835) (xy 0.1651 0.7366) (xy 0.1651 0.44958) (xy 0.17272 0.44196)
						(xy 0.19812 0.4064) (xy 0.2032 0.39624) (xy 0.20701 0.38735) (xy 0.21209 0.37719) (xy 0.2159 0.36703)
						(xy 0.21844 0.35687) (xy 0.22225 0.34544) (xy 0.22352 0.33528) (xy 0.22606 0.32512) (xy 0.22733 0.31369)
						(xy 0.22733 0.30353) (xy 0.2286 0.2921) (xy 0.22733 0.28067) (xy 0.22733 0.27051) (xy 0.22606 0.25908)
						(xy 0.22352 0.24892) (xy 0.22225 0.23876) (xy 0.21844 0.22733) (xy 0.2159 0.21717) (xy 0.21209 0.20701)
						(xy 0.20701 0.19685) (xy 0.2032 0.18796) (xy 0.19812 0.1778) (xy 0.17272 0.14224) (xy 0.1651 0.13462)
						(xy 0.1651 -0.7366) (xy 0.16256 -0.76835) (xy 0.1524 -0.8001) (xy 0.13716 -0.82804) (xy 0.11684 -0.85344)
						(xy 0.09144 -0.87376) (xy 0.0635 -0.889) (xy 0.03175 -0.89916)
					)
					(width 0)
					(fill yes)
				)
			)
		)
		(pad "87" smd custom
			(at -3.450082 -4.100068 180)
			(size 0.1143 0.1143)
			(layers "B.Cu" "B.Mask" "B.Paste")
			(net "M_B_CKE0")
			(options
				(clearance outline)
				(anchor circle)
			)
			(primitives
				(gr_poly
					(pts
						(xy 0 -0.9017) (xy -0.03175 -0.89916) (xy -0.0635 -0.889) (xy -0.09144 -0.87376) (xy -0.11684 -0.85344)
						(xy -0.13716 -0.82804) (xy -0.1524 -0.8001) (xy -0.16256 -0.76835) (xy -0.1651 -0.7366) (xy -0.1651 -0.19685)
						(xy -0.17272 -0.18923) (xy -0.17907 -0.18034) (xy -0.18669 -0.17145) (xy -0.19177 -0.16256) (xy -0.19812 -0.15367)
						(xy -0.20828 -0.13335) (xy -0.21971 -0.10287) (xy -0.22225 -0.09271) (xy -0.22479 -0.08128) (xy -0.22606 -0.07112)
						(xy -0.2286 -0.05969) (xy -0.2286 -0.01651) (xy -0.22606 -0.00508) (xy -0.22479 0.00508) (xy -0.22225 0.01651)
						(xy -0.21971 0.02667) (xy -0.20828 0.05715) (xy -0.19812 0.07747) (xy -0.19177 0.08636) (xy -0.18669 0.09525)
						(xy -0.17907 0.10414) (xy -0.17272 0.11303) (xy -0.1651 0.12065) (xy -0.1651 0.7366) (xy -0.16256 0.76835)
						(xy -0.1524 0.8001) (xy -0.13716 0.82804) (xy -0.11684 0.85344) (xy -0.09144 0.87376) (xy -0.0635 0.889)
						(xy -0.03175 0.89916) (xy 0 0.9017) (xy 0.03175 0.89916) (xy 0.0635 0.889) (xy 0.09144 0.87376)
						(xy 0.11684 0.85344) (xy 0.13716 0.82804) (xy 0.1524 0.8001) (xy 0.16256 0.76835) (xy 0.1651 0.7366)
						(xy 0.1651 0.11938) (xy 0.17272 0.11176) (xy 0.19812 0.0762) (xy 0.2032 0.06604) (xy 0.20701 0.05715)
						(xy 0.21209 0.04699) (xy 0.2159 0.03683) (xy 0.21844 0.02667) (xy 0.22225 0.01524) (xy 0.22352 0.00508)
						(xy 0.22606 -0.00508) (xy 0.22733 -0.01651) (xy 0.22733 -0.02667) (xy 0.2286 -0.0381) (xy 0.22733 -0.04953)
						(xy 0.22733 -0.05969) (xy 0.22606 -0.07112) (xy 0.22352 -0.08128) (xy 0.22225 -0.09144) (xy 0.21844 -0.10287)
						(xy 0.2159 -0.11303) (xy 0.21209 -0.12319) (xy 0.20701 -0.13335) (xy 0.2032 -0.14224) (xy 0.19812 -0.1524)
						(xy 0.17272 -0.18796) (xy 0.1651 -0.19558) (xy 0.1651 -0.7366) (xy 0.16256 -0.76835) (xy 0.1524 -0.8001)
						(xy 0.13716 -0.82804) (xy 0.11684 -0.85344) (xy 0.09144 -0.87376) (xy 0.0635 -0.889) (xy 0.03175 -0.89916)
					)
					(width 0)
					(fill yes)
				)
			)
		)
		(pad "88" smd custom
			(at -3.150108 4.100068 180)
			(size 0.1143 0.1143)
			(layers "B.Cu" "B.Mask" "B.Paste")
			(net "M_B_MA15")
			(options
				(clearance outline)
				(anchor circle)
			)
			(primitives
				(gr_poly
					(pts
						(xy 0 -0.9017) (xy -0.03175 -0.89916) (xy -0.0635 -0.889) (xy -0.09144 -0.87376) (xy -0.11684 -0.85344)
						(xy -0.13716 -0.82804) (xy -0.1524 -0.8001) (xy -0.16256 -0.76835) (xy -0.1651 -0.7366) (xy -0.1651 -0.11938)
						(xy -0.17272 -0.11176) (xy -0.19812 -0.0762) (xy -0.2032 -0.06604) (xy -0.20701 -0.05715) (xy -0.21209 -0.04699)
						(xy -0.2159 -0.03683) (xy -0.21844 -0.02667) (xy -0.22225 -0.01524) (xy -0.22352 -0.00508) (xy -0.22606 0.00508)
						(xy -0.22733 0.01651) (xy -0.22733 0.02667) (xy -0.2286 0.0381) (xy -0.22733 0.04953) (xy -0.22733 0.05969)
						(xy -0.22606 0.07112) (xy -0.22352 0.08128) (xy -0.22225 0.09144) (xy -0.21844 0.10287) (xy -0.2159 0.11303)
						(xy -0.21209 0.12319) (xy -0.20701 0.13335) (xy -0.2032 0.14224) (xy -0.19812 0.1524) (xy -0.17272 0.18796)
						(xy -0.1651 0.19558) (xy -0.1651 0.7366) (xy -0.16256 0.76835) (xy -0.1524 0.8001) (xy -0.13716 0.82804)
						(xy -0.11684 0.85344) (xy -0.09144 0.87376) (xy -0.0635 0.889) (xy -0.03175 0.89916) (xy 0 0.9017)
						(xy 0.03175 0.89916) (xy 0.0635 0.889) (xy 0.09144 0.87376) (xy 0.11684 0.85344) (xy 0.13716 0.82804)
						(xy 0.1524 0.8001) (xy 0.16256 0.76835) (xy 0.1651 0.7366) (xy 0.1651 0.19685) (xy 0.17272 0.18923)
						(xy 0.17907 0.18034) (xy 0.18669 0.17145) (xy 0.19177 0.16256) (xy 0.19812 0.15367) (xy 0.20828 0.13335)
						(xy 0.21971 0.10287) (xy 0.22225 0.09271) (xy 0.22479 0.08128) (xy 0.22606 0.07112) (xy 0.2286 0.05969)
						(xy 0.2286 0.01651) (xy 0.22606 0.00508) (xy 0.22479 -0.00508) (xy 0.22225 -0.01651) (xy 0.21971 -0.02667)
						(xy 0.20828 -0.05715) (xy 0.19812 -0.07747) (xy 0.19177 -0.08636) (xy 0.18669 -0.09525) (xy 0.17907 -0.10414)
						(xy 0.17272 -0.11303) (xy 0.1651 -0.12065) (xy 0.1651 -0.7366) (xy 0.16256 -0.76835) (xy 0.1524 -0.8001)
						(xy 0.13716 -0.82804) (xy 0.11684 -0.85344) (xy 0.09144 -0.87376) (xy 0.0635 -0.889) (xy 0.03175 -0.89916)
					)
					(width 0)
					(fill yes)
				)
			)
		)
		(pad "89" smd custom
			(at -2.84988 -4.100068 180)
			(size 0.1143 0.1143)
			(layers "B.Cu" "B.Mask" "B.Paste")
			(net "M_B_CKE1")
			(options
				(clearance outline)
				(anchor circle)
			)
			(primitives
				(gr_poly
					(pts
						(xy 0 -0.9017) (xy -0.03175 -0.89916) (xy -0.0635 -0.889) (xy -0.09144 -0.87376) (xy -0.11684 -0.85344)
						(xy -0.13716 -0.82804) (xy -0.1524 -0.8001) (xy -0.16256 -0.76835) (xy -0.1651 -0.7366) (xy -0.1651 -0.44958)
						(xy -0.17272 -0.44196) (xy -0.19812 -0.4064) (xy -0.2032 -0.39624) (xy -0.20701 -0.38735) (xy -0.21209 -0.37719)
						(xy -0.2159 -0.36703) (xy -0.21844 -0.35687) (xy -0.22225 -0.34544) (xy -0.22352 -0.33528) (xy -0.22606 -0.32512)
						(xy -0.22733 -0.31369) (xy -0.22733 -0.30353) (xy -0.2286 -0.2921) (xy -0.22733 -0.28067) (xy -0.22733 -0.27051)
						(xy -0.22606 -0.25908) (xy -0.22352 -0.24892) (xy -0.22225 -0.23876) (xy -0.21844 -0.22733) (xy -0.2159 -0.21717)
						(xy -0.21209 -0.20701) (xy -0.20701 -0.19685) (xy -0.2032 -0.18796) (xy -0.19812 -0.1778) (xy -0.17272 -0.14224)
						(xy -0.1651 -0.13462) (xy -0.1651 0.7366) (xy -0.16256 0.76835) (xy -0.1524 0.8001) (xy -0.13716 0.82804)
						(xy -0.11684 0.85344) (xy -0.09144 0.87376) (xy -0.0635 0.889) (xy -0.03175 0.89916) (xy 0 0.9017)
						(xy 0.03175 0.89916) (xy 0.0635 0.889) (xy 0.09144 0.87376) (xy 0.11684 0.85344) (xy 0.13716 0.82804)
						(xy 0.1524 0.8001) (xy 0.16256 0.76835) (xy 0.1651 0.7366) (xy 0.1651 -0.13462) (xy 0.17272 -0.14224)
						(xy 0.19812 -0.1778) (xy 0.2032 -0.18796) (xy 0.20701 -0.19685) (xy 0.21209 -0.20701) (xy 0.2159 -0.21717)
						(xy 0.21844 -0.22733) (xy 0.22225 -0.23876) (xy 0.22352 -0.24892) (xy 0.22606 -0.25908) (xy 0.22733 -0.27051)
						(xy 0.22733 -0.28067) (xy 0.2286 -0.2921) (xy 0.22733 -0.30353) (xy 0.22733 -0.31369) (xy 0.22606 -0.32512)
						(xy 0.22352 -0.33528) (xy 0.22225 -0.34544) (xy 0.21844 -0.35687) (xy 0.2159 -0.36703) (xy 0.21209 -0.37719)
						(xy 0.20701 -0.38735) (xy 0.2032 -0.39624) (xy 0.19812 -0.4064) (xy 0.17272 -0.44196) (xy 0.1651 -0.44958)
						(xy 0.1651 -0.7366) (xy 0.16256 -0.76835) (xy 0.1524 -0.8001) (xy 0.13716 -0.82804) (xy 0.11684 -0.85344)
						(xy 0.09144 -0.87376) (xy 0.0635 -0.889) (xy 0.03175 -0.89916)
					)
					(width 0)
					(fill yes)
				)
			)
		)
		(pad "90" smd custom
			(at -2.549906 4.100068 180)
			(size 0.1143 0.1143)
			(layers "B.Cu" "B.Mask" "B.Paste")
			(net "M_B_MA14")
			(options
				(clearance outline)
				(anchor circle)
			)
			(primitives
				(gr_poly
					(pts
						(xy 0 -0.9017) (xy -0.03175 -0.89916) (xy -0.0635 -0.889) (xy -0.09144 -0.87376) (xy -0.11684 -0.85344)
						(xy -0.13716 -0.82804) (xy -0.1524 -0.8001) (xy -0.16256 -0.76835) (xy -0.1651 -0.7366) (xy -0.1651 0.13462)
						(xy -0.17272 0.14224) (xy -0.19812 0.1778) (xy -0.2032 0.18796) (xy -0.20701 0.19685) (xy -0.21209 0.20701)
						(xy -0.2159 0.21717) (xy -0.21844 0.22733) (xy -0.22225 0.23876) (xy -0.22352 0.24892) (xy -0.22606 0.25908)
						(xy -0.22733 0.27051) (xy -0.22733 0.28067) (xy -0.2286 0.2921) (xy -0.22733 0.30353) (xy -0.22733 0.31369)
						(xy -0.22606 0.32512) (xy -0.22352 0.33528) (xy -0.22225 0.34544) (xy -0.21844 0.35687) (xy -0.2159 0.36703)
						(xy -0.21209 0.37719) (xy -0.20701 0.38735) (xy -0.2032 0.39624) (xy -0.19812 0.4064) (xy -0.17272 0.44196)
						(xy -0.1651 0.44958) (xy -0.1651 0.7366) (xy -0.16256 0.76835) (xy -0.1524 0.8001) (xy -0.13716 0.82804)
						(xy -0.11684 0.85344) (xy -0.09144 0.87376) (xy -0.0635 0.889) (xy -0.03175 0.89916) (xy 0 0.9017)
						(xy 0.03175 0.89916) (xy 0.0635 0.889) (xy 0.09144 0.87376) (xy 0.11684 0.85344) (xy 0.13716 0.82804)
						(xy 0.1524 0.8001) (xy 0.16256 0.76835) (xy 0.1651 0.7366) (xy 0.1651 0.44958) (xy 0.17272 0.44196)
						(xy 0.19812 0.4064) (xy 0.2032 0.39624) (xy 0.20701 0.38735) (xy 0.21209 0.37719) (xy 0.2159 0.36703)
						(xy 0.21844 0.35687) (xy 0.22225 0.34544) (xy 0.22352 0.33528) (xy 0.22606 0.32512) (xy 0.22733 0.31369)
						(xy 0.22733 0.30353) (xy 0.2286 0.2921) (xy 0.22733 0.28067) (xy 0.22733 0.27051) (xy 0.22606 0.25908)
						(xy 0.22352 0.24892) (xy 0.22225 0.23876) (xy 0.21844 0.22733) (xy 0.2159 0.21717) (xy 0.21209 0.20701)
						(xy 0.20701 0.19685) (xy 0.2032 0.18796) (xy 0.19812 0.1778) (xy 0.17272 0.14224) (xy 0.1651 0.13462)
						(xy 0.1651 -0.7366) (xy 0.16256 -0.76835) (xy 0.1524 -0.8001) (xy 0.13716 -0.82804) (xy 0.11684 -0.85344)
						(xy 0.09144 -0.87376) (xy 0.0635 -0.889) (xy 0.03175 -0.89916)
					)
					(width 0)
					(fill yes)
				)
			)
		)
	)
)
